(kicad_pcb
	(version 20260206)
	(generator "pcbnew")
	(generator_version "10.0")
	(general
		(thickness 1.6)
		(legacy_teardrops no)
	)
	(paper "A4")
	(title_block
		(title "Wiwynn_Tioga_Pass_MB.brd")
		(comment 1 "Tioga Pass / footprint 190 of 4770 (U2D1), pads 521-626 of 3647")
	)
	(layers
		(0 "F.Cu" signal "TOP")
		(4 "In1.Cu" signal "L2GND")
		(6 "In2.Cu" signal "L3")
		(8 "In3.Cu" signal "L4GND")
		(10 "In4.Cu" signal "L5")
		(12 "In5.Cu" signal "L6GND")
		(14 "In6.Cu" signal "L7VCC")
		(16 "In7.Cu" signal "L8VCC")
		(18 "In8.Cu" signal "L9GND")
		(20 "In9.Cu" signal "L10")
		(22 "In10.Cu" signal "L11GND")
		(24 "In11.Cu" signal "L12")
		(26 "In12.Cu" signal "L13GND")
		(2 "B.Cu" signal "BOTTOM")
		(9 "F.Adhes" user "F.Adhesive")
		(11 "B.Adhes" user "B.Adhesive")
		(13 "F.Paste" user "Package Geometry/Pastemask Top")
		(15 "B.Paste" user "Package Geometry/Pastemask Bottom")
		(5 "F.SilkS" user "Ref Des/Silkscreen Top")
		(7 "B.SilkS" user "Ref Des/Silkscreen Bottom")
		(1 "F.Mask" user "Board Geometry/Soldermask Top")
		(3 "B.Mask" user "Board Geometry/Soldermask Bottom")
		(17 "Dwgs.User" user "User.Drawings")
		(19 "Cmts.User" user "User.Comments")
		(21 "Eco1.User" user "User.Eco1")
		(23 "Eco2.User" user "User.Eco2")
		(25 "Edge.Cuts" user "Board Geometry/Outline")
		(27 "Margin" user)
		(31 "F.CrtYd" user "Package Geometry/Place Bound Top")
		(29 "B.CrtYd" user "Package Geometry/Place Bound Bottom")
		(35 "F.Fab" user "Ref Des/Assembly Top")
		(33 "B.Fab" user "Ref Des/Assembly Bottom")
	)
	(footprint ""
		(layer "F.Cu")
		(at 104.99979 -76.550012 180)
		(property "Reference" "U2D1"
			(at 25.19299 30.484318 0)
			(unlocked yes)
			(layer "F.SilkS")
			(effects
				(font
					(size 0.7874 0.5842)
					(thickness 0.1524)
				)
			)
		)
		(property "Value" ""
			(at 0 0 180)
			(layer "F.Fab")
			(effects
				(font
					(size 1.27 1.27)
				)
			)
		)
		(duplicate_pad_numbers_are_jumpers no)
		(pad "AN80" smd circle
			(at 32.099504 -11.053572)
			(size 0.4318 0.4318)
			(layers "F.Cu" "F.Mask" "F.Paste")
			(net "M_H_DQ<7>")
		)
		(pad "AN82" smd circle
			(at 33.816544 -11.053572)
			(size 0.4318 0.4318)
			(layers "F.Cu" "F.Mask" "F.Paste")
			(net "M_H_DQ<2>")
		)
		(pad "AN84" smd circle
			(at 35.533584 -11.053572)
			(size 0.4318 0.4318)
			(layers "F.Cu" "F.Mask" "F.Paste")
			(net "M_G_DQ<1>")
		)
		(pad "AN86" smd custom
			(at 37.250624 -11.053572 270)
			(size 0.10795 0.10795)
			(layers "F.Cu" "F.Mask" "F.Paste")
			(net "M_G_DQ<0>")
			(options
				(clearance outline)
				(anchor circle)
			)
			(primitives
				(gr_poly
					(pts
						(arc
							(start 0.2159 -0.0381)
							(mid 0 -0.254)
							(end -0.2159 -0.0381)
						)
						(arc
							(start -0.2159 0.0381)
							(mid 0 0.254)
							(end 0.2159 0.0381)
						)
					)
					(width 0)
					(fill yes)
				)
			)
		)
		(pad "AP1" smd custom
			(at -37.250624 -8.758428 90)
			(size 0.10795 0.10795)
			(layers "F.Cu" "F.Mask" "F.Paste")
			(net "UPI_CPU1_CPU0_P0P0_DN<12>")
			(options
				(clearance outline)
				(anchor circle)
			)
			(primitives
				(gr_poly
					(pts
						(arc
							(start 0.2159 -0.0381)
							(mid 0 -0.254)
							(end -0.2159 -0.0381)
						)
						(arc
							(start -0.2159 0.0381)
							(mid 0 0.254)
							(end 0.2159 0.0381)
						)
					)
					(width 0)
					(fill yes)
				)
			)
		)
		(pad "AP3" smd circle
			(at -35.533584 -8.758428)
			(size 0.4318 0.4318)
			(layers "F.Cu" "F.Mask" "F.Paste")
			(net "UPI_CPU1_CPU0_P0P0_DN<11>")
		)
		(pad "AP5" smd circle
			(at -33.816544 -8.758428)
			(size 0.4318 0.4318)
			(layers "F.Cu" "F.Mask" "F.Paste")
			(net "GND")
		)
		(pad "AP7" smd circle
			(at -32.099504 -8.758428)
			(size 0.4318 0.4318)
			(layers "F.Cu" "F.Mask" "F.Paste")
			(net "UPI_CPU0_CPU1_P0P0_DN<10>")
		)
		(pad "AP9" smd circle
			(at -30.382464 -8.758428)
			(size 0.4318 0.4318)
			(layers "F.Cu" "F.Mask" "F.Paste")
			(net "GND")
		)
		(pad "AP11" smd circle
			(at -28.665424 -8.758428)
			(size 0.4318 0.4318)
			(layers "F.Cu" "F.Mask" "F.Paste")
			(net "TP_CPU1_NMI")
		)
		(pad "AP13" smd circle
			(at -26.948384 -8.758428)
			(size 0.4318 0.4318)
			(layers "F.Cu" "F.Mask" "F.Paste")
			(net "GND")
		)
		(pad "AP17" smd circle
			(at -23.514558 -8.758428)
			(size 0.4318 0.4318)
			(layers "F.Cu" "F.Mask" "F.Paste")
			(net "XDP_CPU_PWR_DEBUG_N")
		)
		(pad "AP19" smd circle
			(at -21.797518 -8.758428)
			(size 0.4318 0.4318)
			(layers "F.Cu" "F.Mask" "F.Paste")
			(net "GND")
		)
		(pad "AP21" smd circle
			(at -20.080478 -8.758428)
			(size 0.4318 0.4318)
			(layers "F.Cu" "F.Mask" "F.Paste")
			(net "RST_CPU1_G_N")
		)
		(pad "AP23" smd circle
			(at -18.363438 -8.758428)
			(size 0.4318 0.4318)
			(layers "F.Cu" "F.Mask" "F.Paste")
			(net "PVCCMCP_CPU1")
		)
		(pad "AP25" smd circle
			(at -16.646398 -8.758428)
			(size 0.4318 0.4318)
			(layers "F.Cu" "F.Mask" "F.Paste")
			(net "PVCCMCP_CPU1")
		)
		(pad "AP27" smd circle
			(at -14.929612 -8.758428)
			(size 0.4318 0.4318)
			(layers "F.Cu" "F.Mask" "F.Paste")
			(net "CLK_100M_CPU1_RC_REFCLK0_DN")
		)
		(pad "AP29" smd circle
			(at -13.212572 -8.758428)
			(size 0.4318 0.4318)
			(layers "F.Cu" "F.Mask" "F.Paste")
			(net "A_CPU1_UPI01_RBIAS")
		)
		(pad "AP31" smd circle
			(at -11.495532 -8.758428)
			(size 0.4318 0.4318)
			(layers "F.Cu" "F.Mask" "F.Paste")
			(net "GND")
		)
		(pad "AP55" smd circle
			(at 10.637012 -10.558526)
			(size 0.508 0.508)
			(layers "F.Cu" "F.Mask" "F.Paste")
			(net "PVCCIN_CPU1")
		)
		(pad "AP57" smd circle
			(at 12.354052 -10.558526)
			(size 0.4318 0.4318)
			(layers "F.Cu" "F.Mask" "F.Paste")
			(net "PVCCIN_CPU1")
		)
		(pad "AP59" smd circle
			(at 14.071092 -10.558526)
			(size 0.4318 0.4318)
			(layers "F.Cu" "F.Mask" "F.Paste")
			(net "GND")
		)
		(pad "AP61" smd circle
			(at 15.787878 -10.558526)
			(size 0.4318 0.4318)
			(layers "F.Cu" "F.Mask" "F.Paste")
			(net "TP_CPU1_RSVD_194")
		)
		(pad "AP63" smd circle
			(at 17.504918 -10.558526)
			(size 0.4318 0.4318)
			(layers "F.Cu" "F.Mask" "F.Paste")
			(net "GND")
		)
		(pad "AP65" smd circle
			(at 19.221958 -10.558526)
			(size 0.4318 0.4318)
			(layers "F.Cu" "F.Mask" "F.Paste")
			(net "GND")
		)
		(pad "AP67" smd circle
			(at 20.938998 -10.558526)
			(size 0.4318 0.4318)
			(layers "F.Cu" "F.Mask" "F.Paste")
			(net "GND")
		)
		(pad "AP69" smd circle
			(at 22.656038 -10.558526)
			(size 0.4318 0.4318)
			(layers "F.Cu" "F.Mask" "F.Paste")
			(net "GND")
		)
		(pad "AP73" smd circle
			(at 26.090118 -10.558526)
			(size 0.4318 0.4318)
			(layers "F.Cu" "F.Mask" "F.Paste")
			(net "GND")
		)
		(pad "AP75" smd circle
			(at 27.806904 -10.558526)
			(size 0.4318 0.4318)
			(layers "F.Cu" "F.Mask" "F.Paste")
			(net "GND")
		)
		(pad "AP77" smd circle
			(at 29.523944 -10.558526)
			(size 0.4318 0.4318)
			(layers "F.Cu" "F.Mask" "F.Paste")
			(net "M_J_DQS_DN<9>")
		)
		(pad "AP79" smd circle
			(at 31.240984 -10.558526)
			(size 0.4318 0.4318)
			(layers "F.Cu" "F.Mask" "F.Paste")
			(net "M_H_DQS_DN<0>")
		)
		(pad "AP81" smd circle
			(at 32.958024 -10.558526)
			(size 0.4318 0.4318)
			(layers "F.Cu" "F.Mask" "F.Paste")
			(net "GND")
		)
		(pad "AP83" smd circle
			(at 34.675064 -10.558526)
			(size 0.4318 0.4318)
			(layers "F.Cu" "F.Mask" "F.Paste")
			(net "GND")
		)
		(pad "AP85" smd circle
			(at 36.392104 -10.558526)
			(size 0.4318 0.4318)
			(layers "F.Cu" "F.Mask" "F.Paste")
			(net "GND")
		)
		(pad "AR2" smd circle
			(at -36.392104 -8.262874)
			(size 0.4318 0.4318)
			(layers "F.Cu" "F.Mask" "F.Paste")
			(net "UPI_CPU1_CPU0_P0P0_DN<13>")
		)
		(pad "AR4" smd circle
			(at -34.675064 -8.262874)
			(size 0.4318 0.4318)
			(layers "F.Cu" "F.Mask" "F.Paste")
			(net "UPI_CPU1_CPU0_P0P0_DN<14>")
		)
		(pad "AR6" smd circle
			(at -32.958024 -8.262874)
			(size 0.4318 0.4318)
			(layers "F.Cu" "F.Mask" "F.Paste")
			(net "GND")
		)
		(pad "AR8" smd circle
			(at -31.240984 -8.262874)
			(size 0.4318 0.4318)
			(layers "F.Cu" "F.Mask" "F.Paste")
			(net "UPI_CPU0_CPU1_P0P0_DP<11>")
		)
		(pad "AR10" smd circle
			(at -29.523944 -8.262874)
			(size 0.4318 0.4318)
			(layers "F.Cu" "F.Mask" "F.Paste")
			(net "GND")
		)
		(pad "AR12" smd circle
			(at -27.806904 -8.262874)
			(size 0.4318 0.4318)
			(layers "F.Cu" "F.Mask" "F.Paste")
			(net "XDP_CPU_PREQ_N")
		)
		(pad "AR14" smd circle
			(at -26.090118 -8.262874)
			(size 0.4318 0.4318)
			(layers "F.Cu" "F.Mask" "F.Paste")
			(net "H_PM_SYNC_GTL_R2")
		)
		(pad "AR16" smd circle
			(at -24.373078 -8.262874)
			(size 0.4318 0.4318)
			(layers "F.Cu" "F.Mask" "F.Paste")
			(net "TP_CPU1_TEST_6")
		)
		(pad "AR18" smd circle
			(at -22.656038 -8.262874)
			(size 0.4318 0.4318)
			(layers "F.Cu" "F.Mask" "F.Paste")
			(net "PU_CPU1_SAFE_MODE_BOOT")
		)
		(pad "AR20" smd circle
			(at -20.938998 -8.262874)
			(size 0.4318 0.4318)
			(layers "F.Cu" "F.Mask" "F.Paste")
			(net "PVCCMCP_CPU1")
		)
		(pad "AR22" smd circle
			(at -19.221958 -8.262874)
			(size 0.4318 0.4318)
			(layers "F.Cu" "F.Mask" "F.Paste")
			(net "PVCCMCP_CPU1")
		)
		(pad "AR24" smd circle
			(at -17.504918 -8.262874)
			(size 0.4318 0.4318)
			(layers "F.Cu" "F.Mask" "F.Paste")
			(net "GND")
		)
		(pad "AR26" smd circle
			(at -15.787878 -8.262874)
			(size 0.4318 0.4318)
			(layers "F.Cu" "F.Mask" "F.Paste")
			(net "PVCCMCP_CPU1")
		)
		(pad "AR28" smd circle
			(at -14.071092 -8.262874)
			(size 0.4318 0.4318)
			(layers "F.Cu" "F.Mask" "F.Paste")
			(net "PVCCIO_CPU1")
		)
		(pad "AR30" smd circle
			(at -12.354052 -8.262874)
			(size 0.4318 0.4318)
			(layers "F.Cu" "F.Mask" "F.Paste")
			(net "GND")
		)
		(pad "AR56" smd circle
			(at 11.495532 -10.062972)
			(size 0.508 0.508)
			(layers "F.Cu" "F.Mask" "F.Paste")
			(net "PVCCIN_CPU1")
		)
		(pad "AR58" smd circle
			(at 13.212572 -10.062972)
			(size 0.4318 0.4318)
			(layers "F.Cu" "F.Mask" "F.Paste")
			(net "PVCCIN_CPU1")
		)
		(pad "AR60" smd circle
			(at 14.929612 -10.062972)
			(size 0.4318 0.4318)
			(layers "F.Cu" "F.Mask" "F.Paste")
			(net "GND")
		)
		(pad "AR62" smd circle
			(at 16.646398 -10.062972)
			(size 0.4318 0.4318)
			(layers "F.Cu" "F.Mask" "F.Paste")
			(net "TP_CPU1_RSVD_190")
		)
		(pad "AR64" smd circle
			(at 18.363438 -10.062972)
			(size 0.4318 0.4318)
			(layers "F.Cu" "F.Mask" "F.Paste")
			(net "M_J_DQ<27>")
		)
		(pad "AR66" smd circle
			(at 20.080478 -10.062972)
			(size 0.4318 0.4318)
			(layers "F.Cu" "F.Mask" "F.Paste")
			(net "M_J_DQS_DP<3>")
		)
		(pad "AR68" smd circle
			(at 21.797518 -10.062972)
			(size 0.4318 0.4318)
			(layers "F.Cu" "F.Mask" "F.Paste")
			(net "M_J_DQ<29>")
		)
		(pad "AR72" smd circle
			(at 25.231598 -10.062972)
			(size 0.4318 0.4318)
			(layers "F.Cu" "F.Mask" "F.Paste")
			(net "GND")
		)
		(pad "AR74" smd circle
			(at 26.948384 -10.062972)
			(size 0.4318 0.4318)
			(layers "F.Cu" "F.Mask" "F.Paste")
			(net "M_J_DQ<5>")
		)
		(pad "AR76" smd circle
			(at 28.665424 -10.062972)
			(size 0.4318 0.4318)
			(layers "F.Cu" "F.Mask" "F.Paste")
			(net "M_J_DQ<0>")
		)
		(pad "AR78" smd circle
			(at 30.382464 -10.062972)
			(size 0.4318 0.4318)
			(layers "F.Cu" "F.Mask" "F.Paste")
			(net "GND")
		)
		(pad "AR80" smd circle
			(at 32.099504 -10.062972)
			(size 0.4318 0.4318)
			(layers "F.Cu" "F.Mask" "F.Paste")
			(net "M_H_DQS_DP<0>")
		)
		(pad "AR82" smd circle
			(at 33.816544 -10.062972)
			(size 0.4318 0.4318)
			(layers "F.Cu" "F.Mask" "F.Paste")
			(net "M_H_DQ<6>")
		)
		(pad "AR84" smd circle
			(at 35.533584 -10.062972)
			(size 0.4318 0.4318)
			(layers "F.Cu" "F.Mask" "F.Paste")
			(net "M_G_DQ<5>")
		)
		(pad "AR86" smd custom
			(at 37.250624 -10.062972 270)
			(size 0.10795 0.10795)
			(layers "F.Cu" "F.Mask" "F.Paste")
			(net "M_G_DQ<4>")
			(options
				(clearance outline)
				(anchor circle)
			)
			(primitives
				(gr_poly
					(pts
						(arc
							(start 0.2159 -0.0381)
							(mid 0 -0.254)
							(end -0.2159 -0.0381)
						)
						(arc
							(start -0.2159 0.0381)
							(mid 0 0.254)
							(end 0.2159 0.0381)
						)
					)
					(width 0)
					(fill yes)
				)
			)
		)
		(pad "AT1" smd custom
			(at -37.250624 -7.767828 90)
			(size 0.10795 0.10795)
			(layers "F.Cu" "F.Mask" "F.Paste")
			(net "UPI_CPU1_CPU0_P0P0_DP<12>")
			(options
				(clearance outline)
				(anchor circle)
			)
			(primitives
				(gr_poly
					(pts
						(arc
							(start 0.2159 -0.0381)
							(mid 0 -0.254)
							(end -0.2159 -0.0381)
						)
						(arc
							(start -0.2159 0.0381)
							(mid 0 0.254)
							(end 0.2159 0.0381)
						)
					)
					(width 0)
					(fill yes)
				)
			)
		)
		(pad "AT3" smd circle
			(at -35.533584 -7.767828)
			(size 0.4318 0.4318)
			(layers "F.Cu" "F.Mask" "F.Paste")
			(net "UPI_CPU1_CPU0_P0P0_DP<13>")
		)
		(pad "AT5" smd circle
			(at -33.816544 -7.767828)
			(size 0.4318 0.4318)
			(layers "F.Cu" "F.Mask" "F.Paste")
			(net "PVCCIO_CPU1")
		)
		(pad "AT7" smd circle
			(at -32.099504 -7.767828)
			(size 0.4318 0.4318)
			(layers "F.Cu" "F.Mask" "F.Paste")
			(net "PVCCIO_CPU1")
		)
		(pad "AT9" smd circle
			(at -30.382464 -7.767828)
			(size 0.4318 0.4318)
			(layers "F.Cu" "F.Mask" "F.Paste")
			(net "UPI_CPU0_CPU1_P0P0_DP<12>")
		)
		(pad "AT11" smd circle
			(at -28.665424 -7.767828)
			(size 0.4318 0.4318)
			(layers "F.Cu" "F.Mask" "F.Paste")
			(net "PVCCIO_CPU1")
		)
		(pad "AT13" smd circle
			(at -26.948384 -7.767828)
			(size 0.4318 0.4318)
			(layers "F.Cu" "F.Mask" "F.Paste")
			(net "TP_CPU1_RSVD_189")
		)
		(pad "AT15" smd circle
			(at -25.231598 -7.767828)
			(size 0.4318 0.4318)
			(layers "F.Cu" "F.Mask" "F.Paste")
			(net "GND")
		)
		(pad "AT17" smd circle
			(at -23.514558 -7.767828)
			(size 0.4318 0.4318)
			(layers "F.Cu" "F.Mask" "F.Paste")
			(net "GND")
		)
		(pad "AT19" smd circle
			(at -21.797518 -7.767828)
			(size 0.4318 0.4318)
			(layers "F.Cu" "F.Mask" "F.Paste")
			(net "H_PMSYNC_CLK_24M_CPU1")
		)
		(pad "AT21" smd circle
			(at -20.080478 -7.767828)
			(size 0.4318 0.4318)
			(layers "F.Cu" "F.Mask" "F.Paste")
			(net "GND")
		)
		(pad "AT23" smd circle
			(at -18.363438 -7.767828)
			(size 0.4318 0.4318)
			(layers "F.Cu" "F.Mask" "F.Paste")
			(net "PVCCMCP_CPU1")
		)
		(pad "AT25" smd circle
			(at -16.646398 -7.767828)
			(size 0.4318 0.4318)
			(layers "F.Cu" "F.Mask" "F.Paste")
			(net "PVCCMCP_CPU1")
		)
		(pad "AT27" smd circle
			(at -14.929612 -7.767828)
			(size 0.4318 0.4318)
			(layers "F.Cu" "F.Mask" "F.Paste")
			(net "GND")
		)
		(pad "AT29" smd circle
			(at -13.212572 -7.767828)
			(size 0.4318 0.4318)
			(layers "F.Cu" "F.Mask" "F.Paste")
			(net "A_CPU1_UPI01_RBIAS")
		)
		(pad "AT57" smd circle
			(at 12.354052 -9.567926)
			(size 0.508 0.508)
			(layers "F.Cu" "F.Mask" "F.Paste")
			(net "PVCCIN_CPU1")
		)
		(pad "AT59" smd circle
			(at 14.071092 -9.567926)
			(size 0.4318 0.4318)
			(layers "F.Cu" "F.Mask" "F.Paste")
			(net "PVCCIN_CPU1")
		)
		(pad "AT61" smd circle
			(at 15.787878 -9.567926)
			(size 0.4318 0.4318)
			(layers "F.Cu" "F.Mask" "F.Paste")
			(net "GND")
		)
		(pad "AT63" smd circle
			(at 17.504918 -9.567926)
			(size 0.4318 0.4318)
			(layers "F.Cu" "F.Mask" "F.Paste")
			(net "GND")
		)
		(pad "AT65" smd circle
			(at 19.221958 -9.567926)
			(size 0.4318 0.4318)
			(layers "F.Cu" "F.Mask" "F.Paste")
			(net "M_J_DQ<31>")
		)
		(pad "AT67" smd circle
			(at 20.938998 -9.567926)
			(size 0.4318 0.4318)
			(layers "F.Cu" "F.Mask" "F.Paste")
			(net "M_J_DQ<25>")
		)
		(pad "AT69" smd circle
			(at 22.656038 -9.567926)
			(size 0.4318 0.4318)
			(layers "F.Cu" "F.Mask" "F.Paste")
			(net "GND")
		)
		(pad "AT71" smd circle
			(at 24.373078 -9.567926)
			(size 0.4318 0.4318)
			(layers "F.Cu" "F.Mask" "F.Paste")
			(net "M_J_DQS_DN<17>")
		)
		(pad "AT73" smd circle
			(at 26.090118 -9.567926)
			(size 0.4318 0.4318)
			(layers "F.Cu" "F.Mask" "F.Paste")
			(net "GND")
		)
		(pad "AT75" smd circle
			(at 27.806904 -9.567926)
			(size 0.4318 0.4318)
			(layers "F.Cu" "F.Mask" "F.Paste")
			(net "M_J_DQ<4>")
		)
		(pad "AT77" smd circle
			(at 29.523944 -9.567926)
			(size 0.4318 0.4318)
			(layers "F.Cu" "F.Mask" "F.Paste")
			(net "GND")
		)
		(pad "AT79" smd circle
			(at 31.240984 -9.567926)
			(size 0.4318 0.4318)
			(layers "F.Cu" "F.Mask" "F.Paste")
			(net "M_H_DQ<1>")
		)
		(pad "AT81" smd circle
			(at 32.958024 -9.567926)
			(size 0.4318 0.4318)
			(layers "F.Cu" "F.Mask" "F.Paste")
			(net "M_H_DQS_DP<9>")
		)
		(pad "AT83" smd circle
			(at 34.675064 -9.567926)
			(size 0.4318 0.4318)
			(layers "F.Cu" "F.Mask" "F.Paste")
			(net "GND")
		)
		(pad "AT85" smd circle
			(at 36.392104 -9.567926)
			(size 0.4318 0.4318)
			(layers "F.Cu" "F.Mask" "F.Paste")
			(net "GND")
		)
		(pad "AU2" smd circle
			(at -36.392104 -7.272274)
			(size 0.4318 0.4318)
			(layers "F.Cu" "F.Mask" "F.Paste")
			(net "GND")
		)
		(pad "AU4" smd circle
			(at -34.675064 -7.272274)
			(size 0.4318 0.4318)
			(layers "F.Cu" "F.Mask" "F.Paste")
			(net "UPI_CPU1_CPU0_P0P0_DP<14>")
		)
		(pad "AU6" smd circle
			(at -32.958024 -7.272274)
			(size 0.4318 0.4318)
			(layers "F.Cu" "F.Mask" "F.Paste")
			(net "GND")
		)
		(pad "AU8" smd circle
			(at -31.240984 -7.272274)
			(size 0.4318 0.4318)
			(layers "F.Cu" "F.Mask" "F.Paste")
			(net "UPI_CPU0_CPU1_P0P0_DN<11>")
		)
		(pad "AU10" smd circle
			(at -29.523944 -7.272274)
			(size 0.4318 0.4318)
			(layers "F.Cu" "F.Mask" "F.Paste")
			(net "UPI_CPU0_CPU1_P0P0_DN<12>")
		)
		(pad "AU12" smd circle
			(at -27.806904 -7.272274)
			(size 0.4318 0.4318)
			(layers "F.Cu" "F.Mask" "F.Paste")
			(net "PECI_CPU_G")
		)
		(pad "AU14" smd circle
			(at -26.090118 -7.272274)
			(size 0.4318 0.4318)
			(layers "F.Cu" "F.Mask" "F.Paste")
			(net "H_CPU1_FIVR_FAULT_G")
		)
		(pad "AU16" smd circle
			(at -24.373078 -7.272274)
			(size 0.4318 0.4318)
			(layers "F.Cu" "F.Mask" "F.Paste")
			(net "PU_CPU1_SOCKET_ID_1")
		)
		(pad "AU18" smd circle
			(at -22.656038 -7.272274)
			(size 0.4318 0.4318)
			(layers "F.Cu" "F.Mask" "F.Paste")
			(net "TP_CPU1_TEST_7")
		)
		(pad "AU20" smd circle
			(at -20.938998 -7.272274)
			(size 0.4318 0.4318)
			(layers "F.Cu" "F.Mask" "F.Paste")
			(net "TP_CPU1_SOCKET_ID_2")
		)
		(pad "AU22" smd circle
			(at -19.221958 -7.272274)
			(size 0.4318 0.4318)
			(layers "F.Cu" "F.Mask" "F.Paste")
			(net "PU_CPU1_SOCKET_ID_0")
		)
		(pad "AU24" smd circle
			(at -17.504918 -7.272274)
			(size 0.4318 0.4318)
			(layers "F.Cu" "F.Mask" "F.Paste")
			(net "CLK_100M_CPU1_BCLK0_DN")
		)
	)
)
